(kicad_sch
	(version 20250114)
	(generator "eeschema")
	(generator_version "9.0")
	(paper "A3")
	(title_block
		(title "Thunderbolt to 10GbE adapter")
		(date "2026-04-23")
		(rev "1.1.0")
	)
	(text "Flash For X710"
		(exclude_from_sim no)
		(at 223.012 107.696 0)
		(effects
			(font
				(size 2.54 2.54)
				(thickness 0.508)
				(bold yes)
			)
		)
	)
	(junction
		(at 222.25 121.92)
		(diameter 0)
		(color 0 0 0 0)
	)
	(junction
		(at 203.2 173.99)
		(diameter 0)
		(color 0 0 0 0)
	)
	(junction
		(at 237.49 144.78)
		(diameter 0)
		(color 0 0 0 0)
	)
	(junction
		(at 209.55 121.92)
		(diameter 0)
		(color 0 0 0 0)
	)
	(junction
		(at 237.49 121.92)
		(diameter 0)
		(color 0 0 0 0)
	)
	(junction
		(at 237.49 132.08)
		(diameter 0)
		(color 0 0 0 0)
	)
	(no_connect
		(at 237.49 163.83)
	)
	(bus_entry
		(at 184.15 139.7)
		(size 2.54 2.54)
		(stroke
			(width 0)
			(type default)
		)
	)
	(bus_entry
		(at 184.15 142.24)
		(size 2.54 2.54)
		(stroke
			(width 0)
			(type default)
		)
	)
	(bus_entry
		(at 184.15 132.08)
		(size 2.54 2.54)
		(stroke
			(width 0)
			(type default)
		)
	)
	(bus_entry
		(at 184.15 129.54)
		(size 2.54 2.54)
		(stroke
			(width 0)
			(type default)
		)
	)
	(wire
		(pts
			(xy 252.73 121.92) (xy 245.11 121.92)
		)
		(stroke
			(width 0)
			(type default)
		)
	)
	(wire
		(pts
			(xy 240.03 121.92) (xy 237.49 121.92)
		)
		(stroke
			(width 0)
			(type default)
		)
	)
	(wire
		(pts
			(xy 254 173.99) (xy 237.49 173.99)
		)
		(stroke
			(width 0)
			(type default)
		)
	)
	(wire
		(pts
			(xy 186.69 134.62) (xy 215.9 134.62)
		)
		(stroke
			(width 0)
			(type default)
		)
	)
	(wire
		(pts
			(xy 237.49 147.32) (xy 237.49 144.78)
		)
		(stroke
			(width 0)
			(type default)
		)
	)
	(bus
		(pts
			(xy 184.15 132.08) (xy 184.15 129.54)
		)
		(stroke
			(width 0)
			(type default)
		)
	)
	(bus
		(pts
			(xy 184.15 139.7) (xy 184.15 132.08)
		)
		(stroke
			(width 0)
			(type default)
		)
	)
	(wire
		(pts
			(xy 237.49 132.08) (xy 237.49 135.89)
		)
		(stroke
			(width 0)
			(type default)
		)
	)
	(wire
		(pts
			(xy 237.49 144.78) (xy 234.95 144.78)
		)
		(stroke
			(width 0)
			(type default)
		)
	)
	(wire
		(pts
			(xy 205.74 168.91) (xy 203.2 168.91)
		)
		(stroke
			(width 0)
			(type default)
		)
	)
	(wire
		(pts
			(xy 205.74 121.92) (xy 205.74 124.46)
		)
		(stroke
			(width 0)
			(type default)
		)
	)
	(wire
		(pts
			(xy 190.5 166.37) (xy 205.74 166.37)
		)
		(stroke
			(width 0)
			(type default)
		)
	)
	(wire
		(pts
			(xy 254 168.91) (xy 237.49 168.91)
		)
		(stroke
			(width 0)
			(type default)
		)
	)
	(wire
		(pts
			(xy 237.49 140.97) (xy 237.49 144.78)
		)
		(stroke
			(width 0)
			(type default)
		)
	)
	(wire
		(pts
			(xy 205.74 139.7) (xy 215.9 139.7)
		)
		(stroke
			(width 0)
			(type default)
		)
	)
	(bus
		(pts
			(xy 184.15 139.7) (xy 184.15 142.24)
		)
		(stroke
			(width 0)
			(type default)
		)
	)
	(wire
		(pts
			(xy 203.2 173.99) (xy 203.2 176.53)
		)
		(stroke
			(width 0)
			(type default)
		)
	)
	(bus
		(pts
			(xy 181.61 124.46) (xy 179.07 124.46)
		)
		(stroke
			(width 0)
			(type default)
		)
	)
	(bus
		(pts
			(xy 184.15 129.54) (xy 184.15 127)
		)
		(stroke
			(width 0)
			(type default)
		)
	)
	(wire
		(pts
			(xy 209.55 124.46) (xy 209.55 121.92)
		)
		(stroke
			(width 0)
			(type default)
		)
	)
	(wire
		(pts
			(xy 222.25 121.92) (xy 237.49 121.92)
		)
		(stroke
			(width 0)
			(type default)
		)
	)
	(wire
		(pts
			(xy 186.69 132.08) (xy 215.9 132.08)
		)
		(stroke
			(width 0)
			(type default)
		)
	)
	(wire
		(pts
			(xy 190.5 171.45) (xy 205.74 171.45)
		)
		(stroke
			(width 0)
			(type default)
		)
	)
	(wire
		(pts
			(xy 209.55 121.92) (xy 222.25 121.92)
		)
		(stroke
			(width 0)
			(type default)
		)
	)
	(wire
		(pts
			(xy 186.69 144.78) (xy 215.9 144.78)
		)
		(stroke
			(width 0)
			(type default)
		)
	)
	(wire
		(pts
			(xy 240.03 176.53) (xy 240.03 166.37)
		)
		(stroke
			(width 0)
			(type default)
		)
	)
	(wire
		(pts
			(xy 205.74 129.54) (xy 205.74 139.7)
		)
		(stroke
			(width 0)
			(type default)
		)
	)
	(wire
		(pts
			(xy 209.55 129.54) (xy 209.55 137.16)
		)
		(stroke
			(width 0)
			(type default)
		)
	)
	(wire
		(pts
			(xy 186.69 142.24) (xy 215.9 142.24)
		)
		(stroke
			(width 0)
			(type default)
		)
	)
	(bus
		(pts
			(xy 181.61 124.46) (xy 184.15 127)
		)
		(stroke
			(width 0)
			(type default)
		)
	)
	(wire
		(pts
			(xy 237.49 121.92) (xy 237.49 132.08)
		)
		(stroke
			(width 0)
			(type default)
		)
	)
	(wire
		(pts
			(xy 205.74 121.92) (xy 209.55 121.92)
		)
		(stroke
			(width 0)
			(type default)
		)
	)
	(wire
		(pts
			(xy 222.25 119.38) (xy 222.25 121.92)
		)
		(stroke
			(width 0)
			(type default)
		)
	)
	(wire
		(pts
			(xy 203.2 168.91) (xy 203.2 173.99)
		)
		(stroke
			(width 0)
			(type default)
		)
	)
	(wire
		(pts
			(xy 252.73 119.38) (xy 252.73 121.92)
		)
		(stroke
			(width 0)
			(type default)
		)
	)
	(wire
		(pts
			(xy 237.49 132.08) (xy 234.95 132.08)
		)
		(stroke
			(width 0)
			(type default)
		)
	)
	(wire
		(pts
			(xy 190.5 163.83) (xy 205.74 163.83)
		)
		(stroke
			(width 0)
			(type default)
		)
	)
	(wire
		(pts
			(xy 240.03 166.37) (xy 237.49 166.37)
		)
		(stroke
			(width 0)
			(type default)
		)
	)
	(wire
		(pts
			(xy 205.74 173.99) (xy 203.2 173.99)
		)
		(stroke
			(width 0)
			(type default)
		)
	)
	(wire
		(pts
			(xy 209.55 137.16) (xy 215.9 137.16)
		)
		(stroke
			(width 0)
			(type default)
		)
	)
	(label "FLASH.MOSI"
		(at 187.96 132.08 0)
		(effects
			(font
				(size 1.27 1.27)
			)
			(justify left bottom)
		)
	)
	(label "~{WP}"
		(at 214.63 137.16 180)
		(effects
			(font
				(size 1.27 1.27)
			)
			(justify right bottom)
		)
	)
	(label "+3V3_FLASH"
		(at 236.22 121.92 180)
		(effects
			(font
				(size 1.27 1.27)
			)
			(justify right bottom)
		)
	)
	(label "~{HOLD}"
		(at 214.63 139.7 180)
		(effects
			(font
				(size 1.27 1.27)
			)
			(justify right bottom)
		)
	)
	(label "FLASH.MISO"
		(at 254 173.99 180)
		(effects
			(font
				(size 1.27 1.27)
			)
			(justify right bottom)
		)
	)
	(label "FLASH.~{CE}"
		(at 187.96 144.78 0)
		(effects
			(font
				(size 1.27 1.27)
			)
			(justify left bottom)
		)
	)
	(label "FLASH.~{CE}"
		(at 190.5 166.37 0)
		(effects
			(font
				(size 1.27 1.27)
			)
			(justify left bottom)
		)
	)
	(label "+3V3_FLASH"
		(at 190.5 163.83 0)
		(effects
			(font
				(size 1.27 1.27)
			)
			(justify left bottom)
		)
	)
	(label "FLASH.CLK"
		(at 190.5 171.45 0)
		(effects
			(font
				(size 1.27 1.27)
			)
			(justify left bottom)
		)
	)
	(label "FLASH.CLK"
		(at 187.96 142.24 0)
		(effects
			(font
				(size 1.27 1.27)
			)
			(justify left bottom)
		)
	)
	(label "FLASH.MISO"
		(at 187.96 134.62 0)
		(effects
			(font
				(size 1.27 1.27)
			)
			(justify left bottom)
		)
	)
	(label "FLASH.MOSI"
		(at 254 168.91 180)
		(effects
			(font
				(size 1.27 1.27)
			)
			(justify right bottom)
		)
	)
	(hierarchical_label "FLASH{SPI}"
		(shape bidirectional)
		(at 179.07 124.46 180)
		(effects
			(font
				(size 1.27 1.27)
			)
			(justify right)
		)
	)
	(symbol
		(lib_id "antmicropower:PWR_FLAG")
		(at 222.25 119.38 0)
		(unit 1)
		(exclude_from_sim no)
		(in_bom yes)
		(on_board yes)
		(dnp no)
		(property "Reference" "#FLG034"
			(at 222.25 117.475 0)
			(effects
				(font
					(size 1.27 1.27)
				)
				(hide yes)
			)
		)
		(property "Value" "PWR_FLAG"
			(at 222.25 115.57 0)
			(effects
				(font
					(size 1.27 1.27)
				)
			)
		)
		(property "Footprint" ""
			(at 222.25 119.38 0)
			(effects
				(font
					(size 1.27 1.27)
				)
				(hide yes)
			)
		)
		(property "Datasheet" ""
			(at 222.25 119.38 0)
			(effects
				(font
					(size 1.27 1.27)
				)
				(hide yes)
			)
		)
		(property "Description" ""
			(at 222.25 121.92 0)
			(effects
				(font
					(size 1.27 1.27)
				)
				(justify left bottom)
				(hide yes)
			)
		)
		(pin "1"
		)
		(instances
			(project "thunderbolt-to-10gbe-adapter"
				(path ""
					(reference "#FLG034")
					(unit 1)
				)
			)
		)
	)
	(symbol
		(lib_id "antmicropower:GND")
		(at 203.2 176.53 0)
		(unit 1)
		(exclude_from_sim no)
		(in_bom yes)
		(on_board yes)
		(dnp no)
		(property "Reference" "#PWR0466"
			(at 212.09 179.07 0)
			(effects
				(font
					(size 1.27 1.27)
					(thickness 0.15)
				)
				(justify left bottom)
				(hide yes)
			)
		)
		(property "Value" "GND"
			(at 203.2 180.34 0)
			(effects
				(font
					(size 1.27 1.27)
					(thickness 0.15)
				)
			)
		)
		(property "Footprint" ""
			(at 212.09 184.15 0)
			(effects
				(font
					(size 1.27 1.27)
					(thickness 0.15)
				)
				(justify left bottom)
				(hide yes)
			)
		)
		(property "Datasheet" ""
			(at 212.09 189.23 0)
			(effects
				(font
					(size 1.27 1.27)
					(thickness 0.15)
				)
				(justify left bottom)
				(hide yes)
			)
		)
		(property "Description" ""
			(at 203.2 176.53 0)
			(effects
				(font
					(size 1.27 1.27)
				)
				(hide yes)
			)
		)
		(property "Author" "Antmicro"
			(at 212.09 184.15 0)
			(effects
				(font
					(size 1.27 1.27)
					(thickness 0.15)
				)
				(justify left bottom)
				(hide yes)
			)
		)
		(property "License" "Apache-2.0"
			(at 212.09 186.69 0)
			(effects
				(font
					(size 1.27 1.27)
					(thickness 0.15)
				)
				(justify left bottom)
				(hide yes)
			)
		)
		(pin "1"
		)
		(instances
			(project "thunderbolt-to-10gbe-adapter"
				(path ""
					(reference "#PWR0466")
					(unit 1)
				)
			)
		)
	)
	(symbol
		(lib_id "antmicroDiodesRectifiersSingle:RB521S30T1G")
		(at 240.03 121.92 0)
		(mirror x)
		(unit 1)
		(exclude_from_sim no)
		(in_bom yes)
		(on_board yes)
		(dnp no)
		(fields_autoplaced yes)
		(property "Reference" "D14"
			(at 242.57 115.57 0)
			(effects
				(font
					(size 1.27 1.27)
					(thickness 0.15)
				)
			)
		)
		(property "Value" "RB521S30T1G"
			(at 262.89 106.68 0)
			(effects
				(font
					(size 1.27 1.27)
					(thickness 0.15)
				)
				(justify left bottom)
				(hide yes)
			)
		)
		(property "Footprint" "antmicro-footprints:SOD-523"
			(at 262.89 111.76 0)
			(effects
				(font
					(size 1.27 1.27)
					(thickness 0.15)
				)
				(justify left bottom)
				(hide yes)
			)
		)
		(property "Datasheet" "https://www.onsemi.com/pdf/datasheet/rb521s30t1-d.pdf"
			(at 262.89 109.22 0)
			(effects
				(font
					(size 1.27 1.27)
					(thickness 0.15)
				)
				(justify left bottom)
				(hide yes)
			)
		)
		(property "Description" "Small Signal Schottky Diode, Single, 30 V, 200 mA, 500 mV, 1 A, 125 °C"
			(at 262.89 96.52 0)
			(effects
				(font
					(size 1.27 1.27)
				)
				(justify left bottom)
				(hide yes)
			)
		)
		(property "MPN" "RB521S30T1G"
			(at 242.57 118.11 0)
			(effects
				(font
					(size 1.27 1.27)
					(thickness 0.15)
				)
			)
		)
		(property "Manufacturer" "ON Semiconductor"
			(at 262.89 104.14 0)
			(effects
				(font
					(size 1.27 1.27)
					(thickness 0.15)
				)
				(justify left bottom)
				(hide yes)
			)
		)
		(property "Author" "Antmicro"
			(at 262.89 101.6 0)
			(effects
				(font
					(size 1.27 1.27)
					(thickness 0.15)
				)
				(justify left bottom)
				(hide yes)
			)
		)
		(property "License" "Apache-2.0"
			(at 262.89 99.06 0)
			(effects
				(font
					(size 1.27 1.27)
					(thickness 0.15)
				)
				(justify left bottom)
				(hide yes)
			)
		)
		(pin "1"
		)
		(pin "2"
		)
		(instances
			(project "thunderbolt-to-10gbe-adapter"
				(path ""
					(reference "D14")
					(unit 1)
				)
			)
		)
	)
	(symbol
		(lib_id "antmicroMemory:AT25DF641A-SH")
		(at 215.9 132.08 0)
		(unit 1)
		(exclude_from_sim no)
		(in_bom yes)
		(on_board yes)
		(dnp no)
		(fields_autoplaced yes)
		(property "Reference" "U19"
			(at 225.425 124.46 0)
			(effects
				(font
					(size 1.27 1.27)
					(thickness 0.15)
				)
			)
		)
		(property "Value" "AT25DF641A-SH"
			(at 248.92 139.7 0)
			(effects
				(font
					(size 1.27 1.27)
					(thickness 0.15)
				)
				(justify left bottom)
				(hide yes)
			)
		)
		(property "Footprint" "antmicro-footprints:SOIC-8_5.3x5.3x2mm_P1.27mm"
			(at 248.92 142.24 0)
			(effects
				(font
					(size 1.27 1.27)
					(thickness 0.15)
				)
				(justify left bottom)
				(hide yes)
			)
		)
		(property "Datasheet" "https://eu.mouser.com/datasheet/3/1166/1/REN_DS-AT25DF641A-8693G-022022_unsecure_DST_20220220_1.pdf"
			(at 248.92 144.78 0)
			(effects
				(font
					(size 1.27 1.27)
					(thickness 0.15)
				)
				(justify left bottom)
				(hide yes)
			)
		)
		(property "Description" "NOR Flash 64 Mbit, 3.0V (2.7V to 3.6V), -40C to 85C, SOIC-W 208mil (Tape & Reel), Single, Dual SPI NOR flash"
			(at 248.92 147.32 0)
			(effects
				(font
					(size 1.27 1.27)
					(thickness 0.15)
				)
				(justify left bottom)
				(hide yes)
			)
		)
		(property "MPN" "AT25DF641A-SH-T "
			(at 225.425 127 0)
			(effects
				(font
					(size 1.27 1.27)
					(thickness 0.15)
				)
			)
		)
		(property "Manufacturer" "Renesas"
			(at 248.92 149.86 0)
			(effects
				(font
					(size 1.27 1.27)
					(thickness 0.15)
				)
				(justify left bottom)
				(hide yes)
			)
		)
		(property "Author" "Antmicro"
			(at 248.92 152.4 0)
			(effects
				(font
					(size 1.27 1.27)
					(thickness 0.15)
				)
				(justify left bottom)
				(hide yes)
			)
		)
		(property "License" "Apache-2.0"
			(at 248.92 154.94 0)
			(effects
				(font
					(size 1.27 1.27)
					(thickness 0.15)
				)
				(justify left bottom)
				(hide yes)
			)
		)
		(pin "3"
		)
		(pin "5"
		)
		(pin "4"
		)
		(pin "7"
		)
		(pin "6"
		)
		(pin "2"
		)
		(pin "1"
		)
		(pin "8"
		)
		(instances
			(project "thunderbolt-to-10gbe-adapter"
				(path ""
					(reference "U19")
					(unit 1)
				)
			)
		)
	)
	(symbol
		(lib_id "antmicroResistors0402:R_10k_0402")
		(at 205.74 129.54 270)
		(mirror x)
		(unit 1)
		(exclude_from_sim no)
		(in_bom yes)
		(on_board yes)
		(dnp no)
		(property "Reference" "R224"
			(at 204.47 125.73 90)
			(effects
				(font
					(size 1.27 1.27)
					(thickness 0.15)
				)
				(justify right)
			)
		)
		(property "Value" "R_10k_0402"
			(at 193.04 109.22 0)
			(effects
				(font
					(size 1.27 1.27)
					(thickness 0.15)
				)
				(justify left bottom)
				(hide yes)
			)
		)
		(property "Footprint" "antmicro-footprints:R_0402_1005Metric"
			(at 190.5 109.22 0)
			(effects
				(font
					(size 1.27 1.27)
					(thickness 0.15)
				)
				(justify left bottom)
				(hide yes)
			)
		)
		(property "Datasheet" "https://www.bourns.com/docs/product-datasheets/cr.pdf"
			(at 187.96 109.22 0)
			(effects
				(font
					(size 1.27 1.27)
					(thickness 0.15)
				)
				(justify left bottom)
				(hide yes)
			)
		)
		(property "Description" "SMD Chip Resistor, 10 kohm, ± 1%, 62.5 mW, 0402 [1005 Metric], Thick Film, General Purpose"
			(at 205.74 129.54 0)
			(effects
				(font
					(size 1.27 1.27)
				)
				(hide yes)
			)
		)
		(property "MPN" "CR0402-FX-1002GLF"
			(at 185.42 109.22 0)
			(effects
				(font
					(size 1.27 1.27)
					(thickness 0.15)
				)
				(justify left bottom)
				(hide yes)
			)
		)
		(property "Manufacturer" "Bourns"
			(at 182.88 109.22 0)
			(effects
				(font
					(size 1.27 1.27)
					(thickness 0.15)
				)
				(justify left bottom)
				(hide yes)
			)
		)
		(property "License" "Apache-2.0"
			(at 180.34 109.22 0)
			(effects
				(font
					(size 1.27 1.27)
					(thickness 0.15)
				)
				(justify left bottom)
				(hide yes)
			)
		)
		(property "Author" "Antmicro"
			(at 177.8 109.22 0)
			(effects
				(font
					(size 1.27 1.27)
					(thickness 0.15)
				)
				(justify left bottom)
				(hide yes)
			)
		)
		(property "Val" "10k"
			(at 204.47 128.27 90)
			(effects
				(font
					(size 1.27 1.27)
					(thickness 0.15)
				)
				(justify right)
			)
		)
		(property "Tolerance" "1%"
			(at 195.58 109.22 0)
			(effects
				(font
					(size 1.27 1.27)
				)
				(justify left bottom)
				(hide yes)
			)
		)
		(pin "1"
		)
		(pin "2"
		)
		(instances
			(project "thunderbolt-to-10gbe-adapter"
				(path ""
					(reference "R224")
					(unit 1)
				)
			)
		)
	)
	(symbol
		(lib_id "antmicropower:GND")
		(at 240.03 176.53 0)
		(unit 1)
		(exclude_from_sim no)
		(in_bom yes)
		(on_board yes)
		(dnp no)
		(property "Reference" "#PWR0468"
			(at 248.92 179.07 0)
			(effects
				(font
					(size 1.27 1.27)
					(thickness 0.15)
				)
				(justify left bottom)
				(hide yes)
			)
		)
		(property "Value" "GND"
			(at 240.03 180.34 0)
			(effects
				(font
					(size 1.27 1.27)
					(thickness 0.15)
				)
			)
		)
		(property "Footprint" ""
			(at 248.92 184.15 0)
			(effects
				(font
					(size 1.27 1.27)
					(thickness 0.15)
				)
				(justify left bottom)
				(hide yes)
			)
		)
		(property "Datasheet" ""
			(at 248.92 189.23 0)
			(effects
				(font
					(size 1.27 1.27)
					(thickness 0.15)
				)
				(justify left bottom)
				(hide yes)
			)
		)
		(property "Description" ""
			(at 240.03 176.53 0)
			(effects
				(font
					(size 1.27 1.27)
				)
				(hide yes)
			)
		)
		(property "Author" "Antmicro"
			(at 248.92 184.15 0)
			(effects
				(font
					(size 1.27 1.27)
					(thickness 0.15)
				)
				(justify left bottom)
				(hide yes)
			)
		)
		(property "License" "Apache-2.0"
			(at 248.92 186.69 0)
			(effects
				(font
					(size 1.27 1.27)
					(thickness 0.15)
				)
				(justify left bottom)
				(hide yes)
			)
		)
		(pin "1"
		)
		(instances
			(project "thunderbolt-to-10gbe-adapter"
				(path ""
					(reference "#PWR0468")
					(unit 1)
				)
			)
		)
	)
	(symbol
		(lib_id "antmicropower:+3V3")
		(at 252.73 119.38 0)
		(unit 1)
		(exclude_from_sim no)
		(in_bom yes)
		(on_board yes)
		(dnp no)
		(property "Reference" "#PWR0469"
			(at 267.97 119.38 0)
			(effects
				(font
					(size 1.27 1.27)
					(thickness 0.15)
				)
				(justify left bottom)
				(hide yes)
			)
		)
		(property "Value" "+3V3"
			(at 252.73 115.57 0)
			(effects
				(font
					(size 1.27 1.27)
					(thickness 0.15)
				)
			)
		)
		(property "Footprint" ""
			(at 267.97 127 0)
			(effects
				(font
					(size 1.27 1.27)
					(thickness 0.15)
				)
				(justify left bottom)
				(hide yes)
			)
		)
		(property "Datasheet" ""
			(at 267.97 129.54 0)
			(effects
				(font
					(size 1.27 1.27)
					(thickness 0.15)
				)
				(justify left bottom)
				(hide yes)
			)
		)
		(property "Description" ""
			(at 252.73 119.38 0)
			(effects
				(font
					(size 1.27 1.27)
				)
				(hide yes)
			)
		)
		(property "Author" "Antmicro"
			(at 267.97 121.92 0)
			(effects
				(font
					(size 1.27 1.27)
					(thickness 0.15)
				)
				(justify left bottom)
				(hide yes)
			)
		)
		(property "License" "Apache-2.0"
			(at 267.97 124.46 0)
			(effects
				(font
					(size 1.27 1.27)
					(thickness 0.15)
				)
				(justify left bottom)
				(hide yes)
			)
		)
		(pin "1"
		)
		(instances
			(project "thunderbolt-to-10gbe-adapter"
				(path ""
					(reference "#PWR0469")
					(unit 1)
				)
			)
		)
	)
	(symbol
		(lib_id "antmicroCapacitors0402:C_100n_0402")
		(at 237.49 140.97 90)
		(unit 1)
		(exclude_from_sim no)
		(in_bom yes)
		(on_board yes)
		(dnp no)
		(fields_autoplaced yes)
		(property "Reference" "C310"
			(at 240.03 137.1536 90)
			(effects
				(font
					(size 1.27 1.27)
					(thickness 0.15)
				)
				(justify right)
			)
		)
		(property "Value" "C_100n_0402"
			(at 260.35 125.73 0)
			(effects
				(font
					(size 1.27 1.27)
					(thickness 0.15)
				)
				(justify left bottom)
				(hide yes)
			)
		)
		(property "Footprint" "antmicro-footprints:C_0402_1005Metric"
			(at 262.89 125.73 0)
			(effects
				(font
					(size 1.27 1.27)
					(thickness 0.15)
				)
				(justify left bottom)
				(hide yes)
			)
		)
		(property "Datasheet" "https://www.murata.com/products/productdetail?partno=GRM155R61H104KE14%23"
			(at 265.43 125.73 0)
			(effects
				(font
					(size 1.27 1.27)
					(thickness 0.15)
				)
				(justify left bottom)
				(hide yes)
			)
		)
		(property "Description" "SMD Multilayer Ceramic Capacitor, 0.1 µF, 50 V, 0402 [1005 Metric], ± 10%, X5R, GRM Series"
			(at 237.49 140.97 0)
			(effects
				(font
					(size 1.27 1.27)
				)
				(hide yes)
			)
		)
		(property "MPN" "GRM155R61H104KE14D"
			(at 267.97 125.73 0)
			(effects
				(font
					(size 1.27 1.27)
					(thickness 0.15)
				)
				(justify left bottom)
				(hide yes)
			)
		)
		(property "Val" "100n"
			(at 240.03 139.6936 90)
			(effects
				(font
					(size 1.27 1.27)
					(thickness 0.15)
				)
				(justify right)
			)
		)
		(property "Voltage" "50V"
			(at 247.65 125.73 0)
			(effects
				(font
					(size 1.27 1.27)
					(thickness 0.15)
				)
				(justify left bottom)
				(hide yes)
			)
		)
		(property "Dielectric" "X5R"
			(at 250.19 125.73 0)
			(effects
				(font
					(size 1.27 1.27)
					(thickness 0.15)
				)
				(justify left bottom)
				(hide yes)
			)
		)
		(property "Manufacturer" "Murata"
			(at 252.73 125.73 0)
			(effects
				(font
					(size 1.27 1.27)
					(thickness 0.15)
				)
				(justify left bottom)
				(hide yes)
			)
		)
		(property "License" "Apache-2.0"
			(at 255.27 125.73 0)
			(effects
				(font
					(size 1.27 1.27)
					(thickness 0.15)
				)
				(justify left bottom)
				(hide yes)
			)
		)
		(property "Author" "Antmicro"
			(at 257.81 125.73 0)
			(effects
				(font
					(size 1.27 1.27)
					(thickness 0.15)
				)
				(justify left bottom)
				(hide yes)
			)
		)
		(pin "2"
		)
		(pin "1"
		)
		(instances
			(project "thunderbolt-to-10gbe-adapter"
				(path ""
					(reference "C310")
					(unit 1)
				)
			)
		)
	)
	(symbol
		(lib_id "antmicroResistors0402:R_10k_0402")
		(at 209.55 129.54 90)
		(unit 1)
		(exclude_from_sim no)
		(in_bom yes)
		(on_board yes)
		(dnp no)
		(property "Reference" "R225"
			(at 210.82 125.73 90)
			(effects
				(font
					(size 1.27 1.27)
					(thickness 0.15)
				)
				(justify right)
			)
		)
		(property "Value" "R_10k_0402"
			(at 222.25 109.22 0)
			(effects
				(font
					(size 1.27 1.27)
					(thickness 0.15)
				)
				(justify left bottom)
				(hide yes)
			)
		)
		(property "Footprint" "antmicro-footprints:R_0402_1005Metric"
			(at 224.79 109.22 0)
			(effects
				(font
					(size 1.27 1.27)
					(thickness 0.15)
				)
				(justify left bottom)
				(hide yes)
			)
		)
		(property "Datasheet" "https://www.bourns.com/docs/product-datasheets/cr.pdf"
			(at 227.33 109.22 0)
			(effects
				(font
					(size 1.27 1.27)
					(thickness 0.15)
				)
				(justify left bottom)
				(hide yes)
			)
		)
		(property "Description" "SMD Chip Resistor, 10 kohm, ± 1%, 62.5 mW, 0402 [1005 Metric], Thick Film, General Purpose"
			(at 209.55 129.54 0)
			(effects
				(font
					(size 1.27 1.27)
				)
				(hide yes)
			)
		)
		(property "MPN" "CR0402-FX-1002GLF"
			(at 229.87 109.22 0)
			(effects
				(font
					(size 1.27 1.27)
					(thickness 0.15)
				)
				(justify left bottom)
				(hide yes)
			)
		)
		(property "Manufacturer" "Bourns"
			(at 232.41 109.22 0)
			(effects
				(font
					(size 1.27 1.27)
					(thickness 0.15)
				)
				(justify left bottom)
				(hide yes)
			)
		)
		(property "License" "Apache-2.0"
			(at 234.95 109.22 0)
			(effects
				(font
					(size 1.27 1.27)
					(thickness 0.15)
				)
				(justify left bottom)
				(hide yes)
			)
		)
		(property "Author" "Antmicro"
			(at 237.49 109.22 0)
			(effects
				(font
					(size 1.27 1.27)
					(thickness 0.15)
				)
				(justify left bottom)
				(hide yes)
			)
		)
		(property "Val" "10k"
			(at 210.82 128.27 90)
			(effects
				(font
					(size 1.27 1.27)
					(thickness 0.15)
				)
				(justify right)
			)
		)
		(property "Tolerance" "1%"
			(at 219.71 109.22 0)
			(effects
				(font
					(size 1.27 1.27)
				)
				(justify left bottom)
				(hide yes)
			)
		)
		(pin "1"
		)
		(pin "2"
		)
		(instances
			(project "thunderbolt-to-10gbe-adapter"
				(path ""
					(reference "R225")
					(unit 1)
				)
			)
		)
	)
	(symbol
		(lib_id "antmicroTestPoints:Tag-Connect_TC2050-IDC-NL_2x5_P1.27mm")
		(at 205.74 163.83 0)
		(unit 1)
		(exclude_from_sim no)
		(in_bom no)
		(on_board yes)
		(dnp yes)
		(property "Reference" "J8"
			(at 221.615 156.21 0)
			(effects
				(font
					(size 1.27 1.27)
					(thickness 0.15)
				)
			)
		)
		(property "Value" "Tag-Connect_TC2050-IDC-NL_2x5_P1.27mm"
			(at 245.11 167.64 0)
			(effects
				(font
					(size 1.27 1.27)
					(thickness 0.15)
				)
				(justify left bottom)
				(hide yes)
			)
		)
		(property "Footprint" "antmicro-footprints:Tag-Connect_TC2050-IDC-NL_2x5_P1.27mm"
			(at 245.11 170.18 0)
			(effects
				(font
					(size 1.27 1.27)
					(thickness 0.15)
				)
				(justify left bottom)
				(hide yes)
			)
		)
		(property "Datasheet" "https://www.tag-connect.com/wp-content/uploads/bsk-pdf-manager/TC2050-IDC-NL_Datasheet_8.pdf"
			(at 245.11 172.72 0)
			(effects
				(font
					(size 1.27 1.27)
					(thickness 0.15)
				)
				(justify left bottom)
				(hide yes)
			)
		)
		(property "Description" "Tag Connect 2x5 1.27mm terminal"
			(at 245.11 185.42 0)
			(effects
				(font
					(size 1.27 1.27)
				)
				(justify left bottom)
				(hide yes)
			)
		)
		(property "MPN" "TC2050-IDC-NL"
			(at 221.615 158.75 0)
			(effects
				(font
					(size 1.27 1.27)
					(thickness 0.15)
				)
			)
		)
		(property "Manufacturer" "Tag Connect"
			(at 245.11 177.8 0)
			(effects
				(font
					(size 1.27 1.27)
					(thickness 0.15)
				)
				(justify left bottom)
				(hide yes)
			)
		)
		(property "Author" "Antmicro"
			(at 245.11 180.34 0)
			(effects
				(font
					(size 1.27 1.27)
					(thickness 0.15)
				)
				(justify left bottom)
				(hide yes)
			)
		)
		(property "License" "Apache-2.0"
			(at 245.11 182.88 0)
			(effects
				(font
					(size 1.27 1.27)
					(thickness 0.15)
				)
				(justify left bottom)
				(hide yes)
			)
		)
		(pin "3"
			(alternate "GND")
		)
		(pin "5"
			(alternate "GND")
		)
		(pin "8"
			(alternate "SPI_MOSI")
		)
		(pin "7"
			(alternate "NC")
		)
		(pin "6"
			(alternate "SPI_MISO")
		)
		(pin "10"
			(alternate "SPI_NC")
		)
		(pin "4"
			(alternate "SPI_SCK")
		)
		(pin "2"
			(alternate "SPI_CS")
		)
		(pin "9"
			(alternate "GND")
		)
		(pin "1"
			(alternate "3V3")
		)
		(instances
			(project "thunderbolt-to-10gbe-adapter"
				(path ""
					(reference "J8")
					(unit 1)
				)
			)
		)
	)
	(symbol
		(lib_id "antmicropower:GND")
		(at 237.49 147.32 0)
		(unit 1)
		(exclude_from_sim no)
		(in_bom yes)
		(on_board yes)
		(dnp no)
		(property "Reference" "#PWR0467"
			(at 246.38 149.86 0)
			(effects
				(font
					(size 1.27 1.27)
					(thickness 0.15)
				)
				(justify left bottom)
				(hide yes)
			)
		)
		(property "Value" "GND"
			(at 237.49 151.13 0)
			(effects
				(font
					(size 1.27 1.27)
					(thickness 0.15)
				)
			)
		)
		(property "Footprint" ""
			(at 246.38 154.94 0)
			(effects
				(font
					(size 1.27 1.27)
					(thickness 0.15)
				)
				(justify left bottom)
				(hide yes)
			)
		)
		(property "Datasheet" ""
			(at 246.38 160.02 0)
			(effects
				(font
					(size 1.27 1.27)
					(thickness 0.15)
				)
				(justify left bottom)
				(hide yes)
			)
		)
		(property "Description" ""
			(at 237.49 147.32 0)
			(effects
				(font
					(size 1.27 1.27)
				)
				(hide yes)
			)
		)
		(property "Author" "Antmicro"
			(at 246.38 154.94 0)
			(effects
				(font
					(size 1.27 1.27)
					(thickness 0.15)
				)
				(justify left bottom)
				(hide yes)
			)
		)
		(property "License" "Apache-2.0"
			(at 246.38 157.48 0)
			(effects
				(font
					(size 1.27 1.27)
					(thickness 0.15)
				)
				(justify left bottom)
				(hide yes)
			)
		)
		(pin "1"
		)
		(instances
			(project "thunderbolt-to-10gbe-adapter"
				(path ""
					(reference "#PWR0467")
					(unit 1)
				)
			)
		)
	)
)
